(kicad_pcb
	(version 20241229)
	(generator "pcbnew")
	(generator_version "9.0")
	(general
		(thickness 1.61)
		(legacy_teardrops no)
	)
	(paper "A3")
	(title_block
		(title "RDIMM DDR5 Tester")
		(date "2026-05-21")
		(rev "2.2.0")
		(company "Antmicro")
		(comment 9 "footprints 562-566 of 796")
	)
	(layers
		(0 "F.Cu" signal)
		(4 "In1.Cu" power)
		(6 "In2.Cu" mixed)
		(8 "In3.Cu" power)
		(10 "In4.Cu" mixed)
		(12 "In5.Cu" power)
		(14 "In6.Cu" mixed)
		(16 "In7.Cu" power)
		(18 "In8.Cu" power)
		(20 "In9.Cu" mixed)
		(22 "In10.Cu" power)
		(2 "B.Cu" signal)
		(9 "F.Adhes" user "F.Adhesive")
		(11 "B.Adhes" user "B.Adhesive")
		(13 "F.Paste" user)
		(15 "B.Paste" user)
		(5 "F.SilkS" user "F.Silkscreen")
		(7 "B.SilkS" user "B.Silkscreen")
		(1 "F.Mask" user)
		(3 "B.Mask" user)
		(17 "Dwgs.User" user "User.Drawings")
		(19 "Cmts.User" user "User.Comments")
		(21 "Eco1.User" user "User.Eco1")
		(23 "Eco2.User" user "User.Eco2")
		(25 "Edge.Cuts" user)
		(27 "Margin" user)
		(31 "F.CrtYd" user "F.Courtyard")
		(29 "B.CrtYd" user "B.Courtyard")
		(35 "F.Fab" user)
		(33 "B.Fab" user)
	)
	(footprint "antmicro-footprints:R_0402_1005Metric"
		(layer "B.Cu")
		(at 253.039499 140.3)
		(descr "Resistor SMD 0402")
		(tags "resistor SMD 0402")
		(property "Reference" "R187"
			(at -4.089499 0.4 0)
			(layer "B.SilkS")
			(effects
				(font
					(size 0.7 0.7)
					(thickness 0.15)
				)
				(justify right bottom mirror)
			)
		)
		(property "Value" "R_47k_0402"
			(at -1.011843 -1.772047 0)
			(layer "B.Fab")
			(effects
				(font
					(size 0.7 0.7)
					(thickness 0.15)
				)
				(justify right bottom mirror)
			)
		)
		(property "Datasheet" "https://www.bourns.com/docs/product-datasheets/cr.pdf"
			(at 0 0 0)
			(layer "F.Fab")
			(hide yes)
			(effects
				(font
					(size 1.27 1.27)
					(thickness 0.15)
				)
			)
		)
		(property "Manufacturer" "Bourns"
			(at 0 0 0)
			(unlocked yes)
			(layer "B.Fab")
			(hide yes)
			(effects
				(font
					(size 1 1)
					(thickness 0.15)
				)
				(justify mirror)
			)
		)
		(property "MPN" "CR0402-FX-4702GLF"
			(at 0 0 0)
			(unlocked yes)
			(layer "B.Fab")
			(hide yes)
			(effects
				(font
					(size 1 1)
					(thickness 0.15)
				)
				(justify mirror)
			)
		)
		(property "Val" "47k"
			(at 0 0 0)
			(unlocked yes)
			(layer "B.Fab")
			(hide yes)
			(effects
				(font
					(size 1 1)
					(thickness 0.15)
				)
				(justify mirror)
			)
		)
		(property "License" "Apache-2.0"
			(at 0 0 0)
			(unlocked yes)
			(layer "B.Fab")
			(hide yes)
			(effects
				(font
					(size 1 1)
					(thickness 0.15)
				)
				(justify mirror)
			)
		)
		(property "Author" "Antmicro"
			(at 0 0 0)
			(unlocked yes)
			(layer "B.Fab")
			(hide yes)
			(effects
				(font
					(size 1 1)
					(thickness 0.15)
				)
				(justify mirror)
			)
		)
		(property "Tolerance" "1%"
			(at 0 0 0)
			(unlocked yes)
			(layer "B.Fab")
			(hide yes)
			(effects
				(font
					(size 1 1)
					(thickness 0.15)
				)
				(justify mirror)
			)
		)
		(sheetname "/Supply/")
		(sheetfile "supply.kicad_sch")
		(attr smd)
		(fp_rect
			(start -0.925 0.47)
			(end 0.925 -0.47)
			(stroke
				(width 0.05)
				(type default)
			)
			(fill no)
			(layer "B.CrtYd")
		)
		(fp_rect
			(start -0.5 0.25)
			(end 0.5 -0.25)
			(stroke
				(width 0.15)
				(type solid)
			)
			(fill no)
			(layer "B.Fab")
		)
		(fp_text user "License: Apache-2.0"
			(at -0.95 -5.169 180)
			(layer "B.Fab")
			(effects
				(font
					(size 0.7 0.7)
					(thickness 0.15)
				)
				(justify left bottom mirror)
			)
		)
		(fp_text user "${REFERENCE}"
			(at -0.95 -3.168 180)
			(layer "B.Fab")
			(effects
				(font
					(size 0.7 0.7)
					(thickness 0.15)
				)
				(justify left bottom mirror)
			)
		)
		(fp_text user "Author: Antmicro"
			(at -0.95 -4.169 180)
			(layer "B.Fab")
			(effects
				(font
					(size 0.7 0.7)
					(thickness 0.15)
				)
				(justify left bottom mirror)
			)
		)
		(pad "1" smd roundrect
			(at -0.48 0)
			(size 0.59 0.64)
			(layers "B.Cu" "B.Mask" "B.Paste")
			(roundrect_rratio 0.25)
			(net 169 "/Supply/EN2")
			(pintype "passive")
		)
		(pad "2" smd roundrect
			(at 0.48 0)
			(size 0.59 0.64)
			(layers "B.Cu" "B.Mask" "B.Paste")
			(roundrect_rratio 0.25)
			(net 38 "+3V3_AON")
			(pintype "passive")
		)
	)
	(footprint "antmicro-footprints:R_0402_1005Metric"
		(layer "B.Cu")
		(at 195.5 136.8 90)
		(descr "Resistor SMD 0402")
		(tags "resistor SMD 0402")
		(property "Reference" "R258"
			(at 2.3 0 270)
			(layer "B.SilkS")
			(effects
				(font
					(size 0.7 0.7)
					(thickness 0.15)
				)
				(justify mirror)
			)
		)
		(property "Value" "R_0R_0402"
			(at -1.011843 -1.772047 270)
			(layer "B.Fab")
			(effects
				(font
					(size 0.7 0.7)
					(thickness 0.15)
				)
				(justify left bottom mirror)
			)
		)
		(property "Datasheet" "https://industrial.panasonic.com/cdbs/www-data/pdf/RDA0000/AOA0000C301.pdf"
			(at 0 0 270)
			(layer "B.Fab")
			(hide yes)
			(effects
				(font
					(size 1.27 1.27)
					(thickness 0.15)
				)
				(justify mirror)
			)
		)
		(property "MPN" "ERJ2GE0R00X"
			(at 0 0 90)
			(unlocked yes)
			(layer "B.Fab")
			(hide yes)
			(effects
				(font
					(size 1 1)
					(thickness 0.15)
				)
				(justify mirror)
			)
		)
		(property "Manufacturer" "Panasonic"
			(at 0 0 90)
			(unlocked yes)
			(layer "B.Fab")
			(hide yes)
			(effects
				(font
					(size 1 1)
					(thickness 0.15)
				)
				(justify mirror)
			)
		)
		(property "License" "Apache-2.0"
			(at 0 0 90)
			(unlocked yes)
			(layer "B.Fab")
			(hide yes)
			(effects
				(font
					(size 1 1)
					(thickness 0.15)
				)
				(justify mirror)
			)
		)
		(property "Author" "Antmicro"
			(at 0 0 90)
			(unlocked yes)
			(layer "B.Fab")
			(hide yes)
			(effects
				(font
					(size 1 1)
					(thickness 0.15)
				)
				(justify mirror)
			)
		)
		(property "Val" "0R"
			(at 0 0 90)
			(unlocked yes)
			(layer "B.Fab")
			(hide yes)
			(effects
				(font
					(size 1 1)
					(thickness 0.15)
				)
				(justify mirror)
			)
		)
		(property "Tolerance" "~"
			(at 0 0 90)
			(unlocked yes)
			(layer "B.Fab")
			(hide yes)
			(effects
				(font
					(size 1 1)
					(thickness 0.15)
				)
				(justify mirror)
			)
		)
		(property "Current" "1A"
			(at 0 0 90)
			(unlocked yes)
			(layer "B.Fab")
			(hide yes)
			(effects
				(font
					(size 1 1)
					(thickness 0.15)
				)
				(justify mirror)
			)
		)
		(sheetname "/FPGA banks HP/")
		(sheetfile "fpga-hp-banks.kicad_sch")
		(attr smd)
		(fp_rect
			(start -0.925 0.47)
			(end 0.925 -0.47)
			(stroke
				(width 0.05)
				(type default)
			)
			(fill no)
			(layer "B.CrtYd")
		)
		(fp_rect
			(start -0.5 0.25)
			(end 0.5 -0.25)
			(stroke
				(width 0.15)
				(type solid)
			)
			(fill no)
			(layer "B.Fab")
		)
		(fp_text user "${REFERENCE}"
			(at -0.95 -3.168 270)
			(layer "B.Fab")
			(effects
				(font
					(size 0.7 0.7)
					(thickness 0.15)
				)
				(justify left bottom mirror)
			)
		)
		(fp_text user "Author: Antmicro"
			(at -0.95 -4.169 270)
			(layer "B.Fab")
			(effects
				(font
					(size 0.7 0.7)
					(thickness 0.15)
				)
				(justify left bottom mirror)
			)
		)
		(fp_text user "License: Apache-2.0"
			(at -0.95 -5.169 270)
			(layer "B.Fab")
			(effects
				(font
					(size 0.7 0.7)
					(thickness 0.15)
				)
				(justify left bottom mirror)
			)
		)
		(pad "1" smd roundrect
			(at -0.48 0 90)
			(size 0.59 0.64)
			(layers "B.Cu" "B.Mask" "B.Paste")
			(roundrect_rratio 0.25)
			(net 536 "/FPGA banks HP/VREF_65")
			(pintype "passive")
		)
		(pad "2" smd roundrect
			(at 0.48 0 90)
			(size 0.59 0.64)
			(layers "B.Cu" "B.Mask" "B.Paste")
			(roundrect_rratio 0.25)
			(net 826 "/FPGA banks HP/VREF")
			(pintype "passive")
		)
	)
	(footprint "antmicro-footprints:C_0402_1005Metric"
		(layer "B.Cu")
		(at 148.074499 160.437 90)
		(descr "Capacitor SMD 0402")
		(tags "capacitor SMD 0402")
		(property "Reference" "C237"
			(at 1.433 0.515501 90)
			(layer "B.SilkS")
			(effects
				(font
					(size 0.7 0.7)
					(thickness 0.15)
				)
				(justify right bottom mirror)
			)
		)
		(property "Value" "C_100n_0402"
			(at -1.022927 -2.155213 90)
			(layer "B.Fab")
			(effects
				(font
					(size 0.7 0.7)
					(thickness 0.15)
				)
				(justify right bottom mirror)
			)
		)
		(property "Datasheet" "https://www.murata.com/products/productdetail?partno=GRM155R61H104KE14%23"
			(at 0 0 90)
			(layer "F.Fab")
			(hide yes)
			(effects
				(font
					(size 1.27 1.27)
					(thickness 0.15)
				)
			)
		)
		(property "MPN" "GRM155R61H104KE14D"
			(at 0 0 90)
			(unlocked yes)
			(layer "B.Fab")
			(hide yes)
			(effects
				(font
					(size 1 1)
					(thickness 0.15)
				)
				(justify mirror)
			)
		)
		(property "Manufacturer" "Murata"
			(at 0 0 90)
			(unlocked yes)
			(layer "B.Fab")
			(hide yes)
			(effects
				(font
					(size 1 1)
					(thickness 0.15)
				)
				(justify mirror)
			)
		)
		(property "License" "Apache-2.0"
			(at 0 0 90)
			(unlocked yes)
			(layer "B.Fab")
			(hide yes)
			(effects
				(font
					(size 1 1)
					(thickness 0.15)
				)
				(justify mirror)
			)
		)
		(property "Author" "Antmicro"
			(at 0 0 90)
			(unlocked yes)
			(layer "B.Fab")
			(hide yes)
			(effects
				(font
					(size 1 1)
					(thickness 0.15)
				)
				(justify mirror)
			)
		)
		(property "Val" "100n"
			(at 0 0 90)
			(unlocked yes)
			(layer "B.Fab")
			(hide yes)
			(effects
				(font
					(size 1 1)
					(thickness 0.15)
				)
				(justify mirror)
			)
		)
		(property "Voltage" "50V"
			(at 0 0 90)
			(unlocked yes)
			(layer "B.Fab")
			(hide yes)
			(effects
				(font
					(size 1 1)
					(thickness 0.15)
				)
				(justify mirror)
			)
		)
		(property "Dielectric" "X5R"
			(at 0 0 90)
			(unlocked yes)
			(layer "B.Fab")
			(hide yes)
			(effects
				(font
					(size 1 1)
					(thickness 0.15)
				)
				(justify mirror)
			)
		)
		(sheetname "/Debug FTDI + VNA/")
		(sheetfile "debug-ftdi.kicad_sch")
		(attr smd)
		(fp_rect
			(start -0.925 0.47)
			(end 0.925 -0.47)
			(stroke
				(width 0.05)
				(type default)
			)
			(fill no)
			(layer "B.CrtYd")
		)
		(fp_line
			(start 0.504 -0.248)
			(end -0.494 -0.248)
			(stroke
				(width 0.15)
				(type solid)
			)
			(layer "B.Fab")
		)
		(fp_line
			(start -0.494 -0.248)
			(end -0.494 0.25)
			(stroke
				(width 0.15)
				(type solid)
			)
			(layer "B.Fab")
		)
		(fp_line
			(start 0.504 0.25)
			(end 0.504 -0.248)
			(stroke
				(width 0.15)
				(type solid)
			)
			(layer "B.Fab")
		)
		(fp_line
			(start -0.494 0.25)
			(end 0.504 0.25)
			(stroke
				(width 0.15)
				(type solid)
			)
			(layer "B.Fab")
		)
		(fp_text user "${REFERENCE}"
			(at -0.939 -4.599 270)
			(layer "B.Fab")
			(effects
				(font
					(size 0.7 0.7)
					(thickness 0.15)
				)
				(justify left bottom mirror)
			)
		)
		(fp_text user "Author: Antmicro"
			(at -0.939 -3.399 270)
			(layer "B.Fab")
			(effects
				(font
					(size 0.7 0.7)
					(thickness 0.15)
				)
				(justify left bottom mirror)
			)
		)
		(fp_text user "License: Apache-2.0"
			(at -0.939 -5.799 270)
			(layer "B.Fab")
			(effects
				(font
					(size 0.7 0.7)
					(thickness 0.15)
				)
				(justify left bottom mirror)
			)
		)
		(pad "1" smd roundrect
			(at -0.48 0 90)
			(size 0.59 0.64)
			(layers "B.Cu" "B.Mask" "B.Paste")
			(roundrect_rratio 0.25)
			(net 1 "GND")
			(pintype "passive")
		)
		(pad "2" smd roundrect
			(at 0.48 0 90)
			(size 0.59 0.64)
			(layers "B.Cu" "B.Mask" "B.Paste")
			(roundrect_rratio 0.25)
			(net 6 "/Debug FTDI + VNA/FTDI_3V3")
			(pintype "passive")
		)
	)
	(footprint "antmicro-footprints:C_0402_1005Metric_EIA"
		(layer "B.Cu")
		(at 200.5 144 180)
		(descr "Capacitor SMD 0402 (1005 Metric), square (rectangular) end terminal, IPC_7351 nominal, (Body size source: IPC-SM-782 page 76, https://www.pcb-3d.com/wordpress/wp-content/uploads/ipc-sm-782a_amendment_1_and_2.pdf)")
		(tags "capacitor 0402")
		(property "Reference" "C37"
			(at -3.275 -0.45 0)
			(layer "B.SilkS")
			(effects
				(font
					(size 0.7 0.7)
					(thickness 0.15)
				)
				(justify left bottom mirror)
			)
		)
		(property "Value" "C_10u_10V_0402"
			(at 0 -1.169 0)
			(layer "B.Fab")
			(effects
				(font
					(size 0.7 0.7)
					(thickness 0.15)
				)
				(justify left bottom mirror)
			)
		)
		(property "Datasheet" "https://www.murata.com/products/productdetail?partno=GRM155R61A106ME11%23"
			(at 0 0 180)
			(layer "F.Fab")
			(hide yes)
			(effects
				(font
					(size 1.27 1.27)
					(thickness 0.15)
				)
			)
		)
		(property "MPN" "GRM155R61A106ME11D"
			(at 0 0 180)
			(unlocked yes)
			(layer "B.Fab")
			(hide yes)
			(effects
				(font
					(size 1 1)
					(thickness 0.15)
				)
				(justify mirror)
			)
		)
		(property "Manufacturer" "Murata"
			(at 0 0 180)
			(unlocked yes)
			(layer "B.Fab")
			(hide yes)
			(effects
				(font
					(size 1 1)
					(thickness 0.15)
				)
				(justify mirror)
			)
		)
		(property "License" "Apache-2.0"
			(at 0 0 180)
			(unlocked yes)
			(layer "B.Fab")
			(hide yes)
			(effects
				(font
					(size 1 1)
					(thickness 0.15)
				)
				(justify mirror)
			)
		)
		(property "Author" "Antmicro"
			(at 0 0 180)
			(unlocked yes)
			(layer "B.Fab")
			(hide yes)
			(effects
				(font
					(size 1 1)
					(thickness 0.15)
				)
				(justify mirror)
			)
		)
		(property "Val" "10u"
			(at 0 0 180)
			(unlocked yes)
			(layer "B.Fab")
			(hide yes)
			(effects
				(font
					(size 1 1)
					(thickness 0.15)
				)
				(justify mirror)
			)
		)
		(property "Voltage" "10V"
			(at 0 0 180)
			(unlocked yes)
			(layer "B.Fab")
			(hide yes)
			(effects
				(font
					(size 1 1)
					(thickness 0.15)
				)
				(justify mirror)
			)
		)
		(property "Dielectric" "X5R"
			(at 0 0 180)
			(unlocked yes)
			(layer "B.Fab")
			(hide yes)
			(effects
				(font
					(size 1 1)
					(thickness 0.15)
				)
				(justify mirror)
			)
		)
		(sheetname "/FPGA power/")
		(sheetfile "fpga-power.kicad_sch")
		(attr smd)
		(fp_rect
			(start -0.95 0.45)
			(end 0.95 -0.45)
			(stroke
				(width 0.05)
				(type default)
			)
			(fill no)
			(layer "B.CrtYd")
		)
		(fp_line
			(start 0.498 0.25)
			(end 0.498 -0.248)
			(stroke
				(width 0.15)
				(type solid)
			)
			(layer "B.Fab")
		)
		(fp_line
			(start 0.498 -0.248)
			(end -0.5 -0.248)
			(stroke
				(width 0.15)
				(type solid)
			)
			(layer "B.Fab")
		)
		(fp_line
			(start -0.5 0.25)
			(end 0.498 0.25)
			(stroke
				(width 0.15)
				(type solid)
			)
			(layer "B.Fab")
		)
		(fp_line
			(start -0.5 -0.248)
			(end -0.5 0.25)
			(stroke
				(width 0.15)
				(type solid)
			)
			(layer "B.Fab")
		)
		(fp_text user "License: Apache-2.0"
			(at -0.9656 -4.369 0)
			(layer "B.Fab")
			(effects
				(font
					(size 0.7 0.7)
					(thickness 0.15)
				)
				(justify left bottom mirror)
			)
		)
		(fp_text user "${REFERENCE}"
			(at -0.9656 -3.169 0)
			(layer "B.Fab")
			(effects
				(font
					(size 0.7 0.7)
					(thickness 0.15)
				)
				(justify left bottom mirror)
			)
		)
		(fp_text user "Author: Antmicro"
			(at -0.9656 -5.569 0)
			(layer "B.Fab")
			(effects
				(font
					(size 0.7 0.7)
					(thickness 0.15)
				)
				(justify left bottom mirror)
			)
		)
		(pad "1" smd roundrect
			(at -0.5 0 90)
			(size 0.6 0.6)
			(layers "B.Cu" "B.Mask" "B.Paste")
			(roundrect_rratio 0.25)
			(net 1 "GND")
			(pintype "passive")
		)
		(pad "2" smd roundrect
			(at 0.498 0 180)
			(size 0.6 0.6)
			(layers "B.Cu" "B.Mask" "B.Paste")
			(roundrect_rratio 0.25)
			(net 687 "VDDQ")
			(pintype "passive")
		)
	)
	(footprint "antmicro-footprints:R_0402_1005Metric"
		(layer "B.Cu")
		(at 168.1 155.55)
		(descr "Resistor SMD 0402")
		(tags "resistor SMD 0402")
		(property "Reference" "R2"
			(at 0.9 0.4 0)
			(layer "B.SilkS")
			(effects
				(font
					(size 0.7 0.7)
					(thickness 0.15)
				)
				(justify right bottom mirror)
			)
		)
		(property "Value" "R_10k_0402"
			(at -1.011843 -1.772047 0)
			(layer "B.Fab")
			(effects
				(font
					(size 0.7 0.7)
					(thickness 0.15)
				)
				(justify right bottom mirror)
			)
		)
		(property "Datasheet" "https://www.bourns.com/docs/product-datasheets/cr.pdf"
			(at 0 0 0)
			(layer "F.Fab")
			(hide yes)
			(effects
				(font
					(size 1.27 1.27)
					(thickness 0.15)
				)
			)
		)
		(property "Manufacturer" "Bourns"
			(at 0 0 0)
			(unlocked yes)
			(layer "B.Fab")
			(hide yes)
			(effects
				(font
					(size 1 1)
					(thickness 0.15)
				)
				(justify mirror)
			)
		)
		(property "MPN" "CR0402-FX-1002GLF"
			(at 0 0 0)
			(unlocked yes)
			(layer "B.Fab")
			(hide yes)
			(effects
				(font
					(size 1 1)
					(thickness 0.15)
				)
				(justify mirror)
			)
		)
		(property "Val" "10k"
			(at 0 0 0)
			(unlocked yes)
			(layer "B.Fab")
			(hide yes)
			(effects
				(font
					(size 1 1)
					(thickness 0.15)
				)
				(justify mirror)
			)
		)
		(property "License" "Apache-2.0"
			(at 0 0 0)
			(unlocked yes)
			(layer "B.Fab")
			(hide yes)
			(effects
				(font
					(size 1 1)
					(thickness 0.15)
				)
				(justify mirror)
			)
		)
		(property "Author" "Antmicro"
			(at 0 0 0)
			(unlocked yes)
			(layer "B.Fab")
			(hide yes)
			(effects
				(font
					(size 1 1)
					(thickness 0.15)
				)
				(justify mirror)
			)
		)
		(property "Tolerance" "1%"
			(at 0 0 0)
			(unlocked yes)
			(layer "B.Fab")
			(hide yes)
			(effects
				(font
					(size 1 1)
					(thickness 0.15)
				)
				(justify mirror)
			)
		)
		(sheetname "/HyperRAM + QSPI Flash/")
		(sheetfile "hyperram-flash.kicad_sch")
		(attr smd)
		(fp_rect
			(start -0.925 0.47)
			(end 0.925 -0.47)
			(stroke
				(width 0.05)
				(type default)
			)
			(fill no)
			(layer "B.CrtYd")
		)
		(fp_rect
			(start -0.5 0.25)
			(end 0.5 -0.25)
			(stroke
				(width 0.15)
				(type solid)
			)
			(fill no)
			(layer "B.Fab")
		)
		(fp_text user "Author: Antmicro"
			(at -0.95 -4.169 180)
			(layer "B.Fab")
			(effects
				(font
					(size 0.7 0.7)
					(thickness 0.15)
				)
				(justify left bottom mirror)
			)
		)
		(fp_text user "License: Apache-2.0"
			(at -0.95 -5.169 180)
			(layer "B.Fab")
			(effects
				(font
					(size 0.7 0.7)
					(thickness 0.15)
				)
				(justify left bottom mirror)
			)
		)
		(fp_text user "${REFERENCE}"
			(at -0.95 -3.168 180)
			(layer "B.Fab")
			(effects
				(font
					(size 0.7 0.7)
					(thickness 0.15)
				)
				(justify left bottom mirror)
			)
		)
		(pad "1" smd roundrect
			(at -0.48 0)
			(size 0.59 0.64)
			(layers "B.Cu" "B.Mask" "B.Paste")
			(roundrect_rratio 0.25)
			(net 797 "+1V8")
			(pintype "passive")
		)
		(pad "2" smd roundrect
			(at 0.48 0)
			(size 0.59 0.64)
			(layers "B.Cu" "B.Mask" "B.Paste")
			(roundrect_rratio 0.25)
			(net 618 "/FPGA banks HP/HyperRAM.~{CS}")
			(pintype "passive")
		)
	)
)
